# S9S_MB_2U (Grand Teton) — schematic netlist excerpt (pin names and nets, part order shuffled) for the footprints in the layout excerpt that follows; sources: Cadence DE-HDL packaged netlist, KiCad conversion of 03242023_DA0F0TMBIJ0_F0T_Motherboard_J_brd_V01_OCP.brd

PC568_P1_2  Q_CAP  22UF 16V 20% X6S  pkg C0805  page 285 : A = SW_P12V_PVCCIN_CPU1_FLT ; B = GND
C356  Q_CAP  47UF 4V 20% X6S  pkg C0805  page 75 : A = PVCCIN_CPU0 ; B = GND
R1310  Q_RES  33.2 1% CHIP  pkg 0402LF  page 205 : A = IRQ_PCH_CPU_NMI_EVENT_R_N ; B = IRQ_PCH_CPU_NMI_EVENT_N

(kicad_pcb
	(version 20260206)
	(generator "pcbnew")
	(generator_version "10.0")
	(general
		(thickness 1.6)
		(legacy_teardrops no)
	)
	(paper "A4")
	(title_block
		(title "03242023_DA0F0TMBIJ0_F0T_Motherboard_J_brd_V01_OCP.brd")
		(comment 1 "Grand Teton / footprints 5201-5203 of 6105")
	)
	(layers
		(0 "F.Cu" signal "TOP")
		(4 "In1.Cu" signal "GND")
		(6 "In2.Cu" signal "IN1")
		(8 "In3.Cu" signal "GND1")
		(10 "In4.Cu" signal "IN2")
		(12 "In5.Cu" signal "GND2")
		(14 "In6.Cu" signal "IN3")
		(16 "In7.Cu" signal "GND3")
		(18 "In8.Cu" signal "VCC")
		(20 "In9.Cu" signal "VCC1")
		(22 "In10.Cu" signal "GND4")
		(24 "In11.Cu" signal "IN4")
		(26 "In12.Cu" signal "GND5")
		(28 "In13.Cu" signal "IN5")
		(30 "In14.Cu" signal "GND6")
		(32 "In15.Cu" signal "IN6")
		(34 "In16.Cu" signal "GND7")
		(2 "B.Cu" signal "BOTTOM")
		(9 "F.Adhes" user "F.Adhesive")
		(11 "B.Adhes" user "B.Adhesive")
		(13 "F.Paste" user "Package Geometry/Pastemask Top")
		(15 "B.Paste" user "Package Geometry/Pastemask Bottom")
		(5 "F.SilkS" user "Ref Des/Silkscreen Top")
		(7 "B.SilkS" user "Ref Des/Silkscreen Bottom")
		(1 "F.Mask" user "Board Geometry/Soldermask Top")
		(3 "B.Mask" user "Board Geometry/Soldermask Bottom")
		(17 "Dwgs.User" user "User.Drawings")
		(19 "Cmts.User" user "User.Comments")
		(21 "Eco1.User" user "User.Eco1")
		(23 "Eco2.User" user "User.Eco2")
		(25 "Edge.Cuts" user "Board Geometry/Outline")
		(27 "Margin" user)
		(31 "F.CrtYd" user "Package Geometry/Place Bound Top")
		(29 "B.CrtYd" user "Package Geometry/Place Bound Bottom")
		(35 "F.Fab" user "Ref Des/Assembly Top")
		(33 "B.Fab" user "Ref Des/Assembly Bottom")
	)
	(footprint ""
		(layer "B.Cu")
		(at 106.661712 -337.607402 -90)
		(property "Reference" "PC568_P1_2"
			(at 0 0 90)
			(layer "B.SilkS")
			(hide yes)
			(effects
				(font
					(size 1.27 1.27)
				)
				(justify mirror)
			)
		)
		(property "Value" ""
			(at 0 0 90)
			(layer "B.Fab")
			(effects
				(font
					(size 1.27 1.27)
				)
				(justify mirror)
			)
		)
		(duplicate_pad_numbers_are_jumpers no)
		(fp_line
			(start -1.524 0.762)
			(end 1.524 0.762)
			(stroke
				(width 0.1524)
				(type default)
			)
			(layer "B.SilkS")
		)
		(fp_line
			(start 1.524 0.762)
			(end 1.524 -0.762)
			(stroke
				(width 0.1524)
				(type default)
			)
			(layer "B.SilkS")
		)
		(fp_line
			(start -1.524 -0.762)
			(end -1.524 0.762)
			(stroke
				(width 0.1524)
				(type default)
			)
			(layer "B.SilkS")
		)
		(fp_line
			(start 1.524 -0.762)
			(end -1.524 -0.762)
			(stroke
				(width 0.1524)
				(type default)
			)
			(layer "B.SilkS")
		)
		(fp_line
			(start -1.1049 0.724916)
			(end -1.1049 -0.724916)
			(stroke
				(width 0.1)
				(type default)
			)
			(layer "B.Fab")
		)
		(fp_line
			(start 1.1049 0.724916)
			(end -1.1049 0.724916)
			(stroke
				(width 0.1)
				(type default)
			)
			(layer "B.Fab")
		)
		(fp_line
			(start -1.1049 -0.724916)
			(end 1.1049 -0.724916)
			(stroke
				(width 0.1)
				(type default)
			)
			(layer "B.Fab")
		)
		(fp_line
			(start 1.1049 -0.724916)
			(end 1.1049 0.724916)
			(stroke
				(width 0.1)
				(type default)
			)
			(layer "B.Fab")
		)
		(pad "1" smd rect
			(at 0.889 0 270)
			(size 1.016 1.27)
			(layers "B.Cu" "B.Mask" "B.Paste")
			(net "SW_P12V_PVCCIN_CPU1_FLT")
		)
		(pad "2" smd rect
			(at -0.889 0 270)
			(size 1.016 1.27)
			(layers "B.Cu" "B.Mask" "B.Paste")
			(net "GND")
		)
	)
	(footprint ""
		(layer "B.Cu")
		(at 329.646534 -25.803352 -90)
		(property "Reference" "R1310"
			(at 0 0 90)
			(layer "B.SilkS")
			(hide yes)
			(effects
				(font
					(size 1.27 1.27)
				)
				(justify mirror)
			)
		)
		(property "Value" ""
			(at 0 0 90)
			(layer "B.Fab")
			(effects
				(font
					(size 1.27 1.27)
				)
				(justify mirror)
			)
		)
		(duplicate_pad_numbers_are_jumpers no)
		(fp_line
			(start -0.7874 0.4064)
			(end 0.7874 0.4064)
			(stroke
				(width 0.1524)
				(type default)
			)
			(layer "B.SilkS")
		)
		(fp_line
			(start 0.7874 0.4064)
			(end 0.7874 -0.4064)
			(stroke
				(width 0.1524)
				(type default)
			)
			(layer "B.SilkS")
		)
		(fp_line
			(start -0.7874 -0.4064)
			(end -0.7874 0.4064)
			(stroke
				(width 0.1524)
				(type default)
			)
			(layer "B.SilkS")
		)
		(fp_line
			(start 0.7874 -0.4064)
			(end -0.7874 -0.4064)
			(stroke
				(width 0.1524)
				(type default)
			)
			(layer "B.SilkS")
		)
		(fp_line
			(start -0.67945 0.3048)
			(end -0.120396 0.3048)
			(stroke
				(width 0.1)
				(type default)
			)
			(layer "B.Fab")
		)
		(fp_line
			(start -0.120396 0.3048)
			(end -0.120396 0.2794)
			(stroke
				(width 0.1)
				(type default)
			)
			(layer "B.Fab")
		)
		(fp_line
			(start 0.12065 0.3048)
			(end 0.67945 0.3048)
			(stroke
				(width 0.1)
				(type default)
			)
			(layer "B.Fab")
		)
		(fp_line
			(start 0.67945 0.3048)
			(end 0.67945 -0.305054)
			(stroke
				(width 0.1)
				(type default)
			)
			(layer "B.Fab")
		)
		(fp_line
			(start -0.120396 0.2794)
			(end 0.12065 0.2794)
			(stroke
				(width 0.1)
				(type default)
			)
			(layer "B.Fab")
		)
		(fp_line
			(start 0.12065 0.2794)
			(end 0.12065 0.3048)
			(stroke
				(width 0.1)
				(type default)
			)
			(layer "B.Fab")
		)
		(fp_line
			(start -0.12065 -0.2794)
			(end -0.12065 -0.3048)
			(stroke
				(width 0.1)
				(type default)
			)
			(layer "B.Fab")
		)
		(fp_line
			(start 0.12065 -0.2794)
			(end -0.12065 -0.2794)
			(stroke
				(width 0.1)
				(type default)
			)
			(layer "B.Fab")
		)
		(fp_line
			(start -0.67945 -0.3048)
			(end -0.67945 0.3048)
			(stroke
				(width 0.1)
				(type default)
			)
			(layer "B.Fab")
		)
		(fp_line
			(start -0.12065 -0.3048)
			(end -0.67945 -0.3048)
			(stroke
				(width 0.1)
				(type default)
			)
			(layer "B.Fab")
		)
		(fp_line
			(start 0.12065 -0.305054)
			(end 0.12065 -0.2794)
			(stroke
				(width 0.1)
				(type default)
			)
			(layer "B.Fab")
		)
		(fp_line
			(start 0.67945 -0.305054)
			(end 0.12065 -0.305054)
			(stroke
				(width 0.1)
				(type default)
			)
			(layer "B.Fab")
		)
		(pad "1" smd circle
			(at 0.40005 0 90)
			(size 0 0)
			(layers "B.Cu" "B.Mask" "B.Paste")
			(net "IRQ_PCH_CPU_NMI_EVENT_R_N")
		)
		(pad "2" smd circle
			(at -0.40005 0 90)
			(size 0 0)
			(layers "B.Cu" "B.Mask" "B.Paste")
			(net "IRQ_PCH_CPU_NMI_EVENT_N")
		)
	)
	(footprint ""
		(layer "B.Cu")
		(at 353.535742 -262.348726)
		(property "Reference" "C356"
			(at 0 0 0)
			(layer "B.SilkS")
			(hide yes)
			(effects
				(font
					(size 1.27 1.27)
				)
				(justify mirror)
			)
		)
		(property "Value" ""
			(at 0 0 0)
			(layer "B.Fab")
			(effects
				(font
					(size 1.27 1.27)
				)
				(justify mirror)
			)
		)
		(duplicate_pad_numbers_are_jumpers no)
		(fp_line
			(start -1.524 -0.762)
			(end -1.524 0.762)
			(stroke
				(width 0.1524)
				(type default)
			)
			(layer "B.SilkS")
		)
		(fp_line
			(start -1.524 0.762)
			(end 1.524 0.762)
			(stroke
				(width 0.1524)
				(type default)
			)
			(layer "B.SilkS")
		)
		(fp_line
			(start 1.524 -0.762)
			(end -1.524 -0.762)
			(stroke
				(width 0.1524)
				(type default)
			)
			(layer "B.SilkS")
		)
		(fp_line
			(start 1.524 0.762)
			(end 1.524 -0.762)
			(stroke
				(width 0.1524)
				(type default)
			)
			(layer "B.SilkS")
		)
		(fp_line
			(start -1.1049 -0.724916)
			(end 1.1049 -0.724916)
			(stroke
				(width 0.1)
				(type default)
			)
			(layer "B.Fab")
		)
		(fp_line
			(start -1.1049 0.724916)
			(end -1.1049 -0.724916)
			(stroke
				(width 0.1)
				(type default)
			)
			(layer "B.Fab")
		)
		(fp_line
			(start 1.1049 -0.724916)
			(end 1.1049 0.724916)
			(stroke
				(width 0.1)
				(type default)
			)
			(layer "B.Fab")
		)
		(fp_line
			(start 1.1049 0.724916)
			(end -1.1049 0.724916)
			(stroke
				(width 0.1)
				(type default)
			)
			(layer "B.Fab")
		)
		(pad "1" smd rect
			(at 0.889 0)
			(size 1.016 1.27)
			(layers "B.Cu" "B.Mask" "B.Paste")
			(net "PVCCIN_CPU0")
		)
		(pad "2" smd rect
			(at -0.889 0)
			(size 1.016 1.27)
			(layers "B.Cu" "B.Mask" "B.Paste")
			(net "GND")
		)
	)
)
